# S9S_MB_2U (Grand Teton) — schematic netlist excerpt (pin names and nets, part order shuffled) for the footprints in the layout excerpt that follows; sources: Cadence DE-HDL packaged netlist, KiCad conversion of 03242023_DA0F0TMBIJ0_F0T_Motherboard_J_brd_V01_OCP.brd

C926  Q_CAP_DIFFBUS  DIFF BUS_0.22UF 6.3V 20% X6S  pkg C0201  page 173 : \1\ = P5E_CPU0_PE0_TX_C_DN<3> ; \2\ = P5E_CPU0_PE0_TX_DN<3>
C718  Q_CAP_DIFFBUS  DIFF BUS_0.22UF 6.3V 20% X6S  pkg C0201  page 176 : \1\ = P5E_CPU1_PE0_TX_C_DN<11> ; \2\ = P5E_CPU1_PE0_TX_DN<11>
R3502  Q_RES  100K 1% EMPTY  pkg 0402LF  page 147 : A = GPU_FPGA_EROT_FATALERR_N ; B = GND

(kicad_pcb
	(version 20260206)
	(generator "pcbnew")
	(generator_version "10.0")
	(general
		(thickness 1.6)
		(legacy_teardrops no)
	)
	(paper "A4")
	(title_block
		(title "03242023_DA0F0TMBIJ0_F0T_Motherboard_J_brd_V01_OCP.brd")
		(comment 1 "Grand Teton / footprints 1674-1676 of 6105")
	)
	(layers
		(0 "F.Cu" signal "TOP")
		(4 "In1.Cu" signal "GND")
		(6 "In2.Cu" signal "IN1")
		(8 "In3.Cu" signal "GND1")
		(10 "In4.Cu" signal "IN2")
		(12 "In5.Cu" signal "GND2")
		(14 "In6.Cu" signal "IN3")
		(16 "In7.Cu" signal "GND3")
		(18 "In8.Cu" signal "VCC")
		(20 "In9.Cu" signal "VCC1")
		(22 "In10.Cu" signal "GND4")
		(24 "In11.Cu" signal "IN4")
		(26 "In12.Cu" signal "GND5")
		(28 "In13.Cu" signal "IN5")
		(30 "In14.Cu" signal "GND6")
		(32 "In15.Cu" signal "IN6")
		(34 "In16.Cu" signal "GND7")
		(2 "B.Cu" signal "BOTTOM")
		(9 "F.Adhes" user "F.Adhesive")
		(11 "B.Adhes" user "B.Adhesive")
		(13 "F.Paste" user "Package Geometry/Pastemask Top")
		(15 "B.Paste" user "Package Geometry/Pastemask Bottom")
		(5 "F.SilkS" user "Ref Des/Silkscreen Top")
		(7 "B.SilkS" user "Ref Des/Silkscreen Bottom")
		(1 "F.Mask" user "Board Geometry/Soldermask Top")
		(3 "B.Mask" user "Board Geometry/Soldermask Bottom")
		(17 "Dwgs.User" user "User.Drawings")
		(19 "Cmts.User" user "User.Comments")
		(21 "Eco1.User" user "User.Eco1")
		(23 "Eco2.User" user "User.Eco2")
		(25 "Edge.Cuts" user "Board Geometry/Outline")
		(27 "Margin" user)
		(31 "F.CrtYd" user "Package Geometry/Place Bound Top")
		(29 "B.CrtYd" user "Package Geometry/Place Bound Bottom")
		(35 "F.Fab" user "Ref Des/Assembly Top")
		(33 "B.Fab" user "Ref Des/Assembly Bottom")
	)
	(footprint ""
		(layer "F.Cu")
		(at 60.207398 -402.371052 -90)
		(property "Reference" "C718"
			(at 0 0 270)
			(layer "F.SilkS")
			(hide yes)
			(effects
				(font
					(size 1.27 1.27)
				)
			)
		)
		(property "Value" ""
			(at 0 0 270)
			(layer "F.Fab")
			(effects
				(font
					(size 1.27 1.27)
				)
			)
		)
		(duplicate_pad_numbers_are_jumpers no)
		(fp_line
			(start -0.299974 0.150114)
			(end -0.299974 -0.150114)
			(stroke
				(width 0.1)
				(type default)
			)
			(layer "F.Fab")
		)
		(fp_line
			(start 0.299974 0.150114)
			(end -0.299974 0.150114)
			(stroke
				(width 0.1)
				(type default)
			)
			(layer "F.Fab")
		)
		(fp_line
			(start -0.299974 -0.150114)
			(end 0.299974 -0.150114)
			(stroke
				(width 0.1)
				(type default)
			)
			(layer "F.Fab")
		)
		(fp_line
			(start 0.299974 -0.150114)
			(end 0.299974 0.150114)
			(stroke
				(width 0.1)
				(type default)
			)
			(layer "F.Fab")
		)
		(pad "1" smd rect
			(at -0.2667 0 270)
			(size 0.3048 0.381)
			(layers "F.Cu" "F.Mask" "F.Paste")
			(net "P5E_CPU1_PE0_TX_C_DN<11>")
		)
		(pad "2" smd rect
			(at 0.2667 0 270)
			(size 0.3048 0.381)
			(layers "F.Cu" "F.Mask" "F.Paste")
			(net "P5E_CPU1_PE0_TX_DN<11>")
		)
	)
	(footprint ""
		(layer "F.Cu")
		(at 95.125286 -427.776386 90)
		(property "Reference" "R3502"
			(at 0 0 90)
			(layer "F.SilkS")
			(hide yes)
			(effects
				(font
					(size 1.27 1.27)
				)
			)
		)
		(property "Value" ""
			(at 0 0 90)
			(layer "F.Fab")
			(effects
				(font
					(size 1.27 1.27)
				)
			)
		)
		(duplicate_pad_numbers_are_jumpers no)
		(fp_line
			(start 0.7874 -0.4064)
			(end 0.7874 0.4064)
			(stroke
				(width 0.1524)
				(type default)
			)
			(layer "F.SilkS")
		)
		(fp_line
			(start -0.7874 -0.4064)
			(end 0.7874 -0.4064)
			(stroke
				(width 0.1524)
				(type default)
			)
			(layer "F.SilkS")
		)
		(fp_line
			(start 0.7874 0.4064)
			(end -0.7874 0.4064)
			(stroke
				(width 0.1524)
				(type default)
			)
			(layer "F.SilkS")
		)
		(fp_line
			(start -0.7874 0.4064)
			(end -0.7874 -0.4064)
			(stroke
				(width 0.1524)
				(type default)
			)
			(layer "F.SilkS")
		)
		(fp_line
			(start -0.12065 -0.305054)
			(end -0.12065 -0.2794)
			(stroke
				(width 0.1)
				(type default)
			)
			(layer "F.Fab")
		)
		(fp_line
			(start -0.67945 -0.305054)
			(end -0.12065 -0.305054)
			(stroke
				(width 0.1)
				(type default)
			)
			(layer "F.Fab")
		)
		(fp_line
			(start 0.67945 -0.3048)
			(end 0.67945 0.3048)
			(stroke
				(width 0.1)
				(type default)
			)
			(layer "F.Fab")
		)
		(fp_line
			(start 0.12065 -0.3048)
			(end 0.67945 -0.3048)
			(stroke
				(width 0.1)
				(type default)
			)
			(layer "F.Fab")
		)
		(fp_line
			(start 0.12065 -0.2794)
			(end 0.12065 -0.3048)
			(stroke
				(width 0.1)
				(type default)
			)
			(layer "F.Fab")
		)
		(fp_line
			(start -0.12065 -0.2794)
			(end 0.12065 -0.2794)
			(stroke
				(width 0.1)
				(type default)
			)
			(layer "F.Fab")
		)
		(fp_line
			(start 0.120396 0.2794)
			(end -0.12065 0.2794)
			(stroke
				(width 0.1)
				(type default)
			)
			(layer "F.Fab")
		)
		(fp_line
			(start -0.12065 0.2794)
			(end -0.12065 0.3048)
			(stroke
				(width 0.1)
				(type default)
			)
			(layer "F.Fab")
		)
		(fp_line
			(start 0.67945 0.3048)
			(end 0.120396 0.3048)
			(stroke
				(width 0.1)
				(type default)
			)
			(layer "F.Fab")
		)
		(fp_line
			(start 0.120396 0.3048)
			(end 0.120396 0.2794)
			(stroke
				(width 0.1)
				(type default)
			)
			(layer "F.Fab")
		)
		(fp_line
			(start -0.12065 0.3048)
			(end -0.67945 0.3048)
			(stroke
				(width 0.1)
				(type default)
			)
			(layer "F.Fab")
		)
		(fp_line
			(start -0.67945 0.3048)
			(end -0.67945 -0.305054)
			(stroke
				(width 0.1)
				(type default)
			)
			(layer "F.Fab")
		)
		(pad "1" smd circle
			(at -0.40005 0 90)
			(size 0 0)
			(layers "F.Cu" "F.Mask" "F.Paste")
			(net "GPU_FPGA_EROT_FATALERR_N")
		)
		(pad "2" smd circle
			(at 0.40005 0 90)
			(size 0 0)
			(layers "F.Cu" "F.Mask" "F.Paste")
			(net "GND")
		)
	)
	(footprint ""
		(layer "F.Cu")
		(at 342.059768 -408.517344 -90)
		(property "Reference" "C926"
			(at 0 0 270)
			(layer "F.SilkS")
			(hide yes)
			(effects
				(font
					(size 1.27 1.27)
				)
			)
		)
		(property "Value" ""
			(at 0 0 270)
			(layer "F.Fab")
			(effects
				(font
					(size 1.27 1.27)
				)
			)
		)
		(duplicate_pad_numbers_are_jumpers no)
		(fp_line
			(start -0.299974 0.150114)
			(end -0.299974 -0.150114)
			(stroke
				(width 0.1)
				(type default)
			)
			(layer "F.Fab")
		)
		(fp_line
			(start 0.299974 0.150114)
			(end -0.299974 0.150114)
			(stroke
				(width 0.1)
				(type default)
			)
			(layer "F.Fab")
		)
		(fp_line
			(start -0.299974 -0.150114)
			(end 0.299974 -0.150114)
			(stroke
				(width 0.1)
				(type default)
			)
			(layer "F.Fab")
		)
		(fp_line
			(start 0.299974 -0.150114)
			(end 0.299974 0.150114)
			(stroke
				(width 0.1)
				(type default)
			)
			(layer "F.Fab")
		)
		(pad "1" smd rect
			(at -0.2667 0 270)
			(size 0.3048 0.381)
			(layers "F.Cu" "F.Mask" "F.Paste")
			(net "P5E_CPU0_PE0_TX_C_DN<3>")
		)
		(pad "2" smd rect
			(at 0.2667 0 270)
			(size 0.3048 0.381)
			(layers "F.Cu" "F.Mask" "F.Paste")
			(net "P5E_CPU0_PE0_TX_DN<3>")
		)
	)
)
